# BASEBOARD_FAB2 (Tioga Pass) — schematic netlist excerpt (pin names and nets, part order shuffled) for the footprints in the layout excerpt that follows; sources: Cadence DE-HDL packaged netlist, KiCad conversion of Wiwynn_Tioga_Pass_MB.brd

C9E7  CAP  0.039UF 25V 10% X7R  pkg 0402LF  page 139 : A = A_CTOP ; B = A_CBOT
C1D34  CAP_A  0.1UF 16V 10% X7R  pkg 0402V  page 207 : A = VR_FET_SW_P12V_STBY_PVCCIN_CPU1 ; B = GND
C8B4  CAP_A  22.0UF 4V 20% X6S  pkg 0603V  page 130 : A = P1V8_PCH_STBY ; B = GND

(kicad_pcb
	(version 20260206)
	(generator "pcbnew")
	(generator_version "10.0")
	(general
		(thickness 1.6)
		(legacy_teardrops no)
	)
	(paper "A4")
	(title_block
		(title "Wiwynn_Tioga_Pass_MB.brd")
		(comment 1 "Tioga Pass / footprints 2106-2108 of 4770")
	)
	(layers
		(0 "F.Cu" signal "TOP")
		(4 "In1.Cu" signal "L2GND")
		(6 "In2.Cu" signal "L3")
		(8 "In3.Cu" signal "L4GND")
		(10 "In4.Cu" signal "L5")
		(12 "In5.Cu" signal "L6GND")
		(14 "In6.Cu" signal "L7VCC")
		(16 "In7.Cu" signal "L8VCC")
		(18 "In8.Cu" signal "L9GND")
		(20 "In9.Cu" signal "L10")
		(22 "In10.Cu" signal "L11GND")
		(24 "In11.Cu" signal "L12")
		(26 "In12.Cu" signal "L13GND")
		(2 "B.Cu" signal "BOTTOM")
		(9 "F.Adhes" user "F.Adhesive")
		(11 "B.Adhes" user "B.Adhesive")
		(13 "F.Paste" user "Package Geometry/Pastemask Top")
		(15 "B.Paste" user "Package Geometry/Pastemask Bottom")
		(5 "F.SilkS" user "Ref Des/Silkscreen Top")
		(7 "B.SilkS" user "Ref Des/Silkscreen Bottom")
		(1 "F.Mask" user "Board Geometry/Soldermask Top")
		(3 "B.Mask" user "Board Geometry/Soldermask Bottom")
		(17 "Dwgs.User" user "User.Drawings")
		(19 "Cmts.User" user "User.Comments")
		(21 "Eco1.User" user "User.Eco1")
		(23 "Eco2.User" user "User.Eco2")
		(25 "Edge.Cuts" user "Board Geometry/Outline")
		(27 "Margin" user)
		(31 "F.CrtYd" user "Package Geometry/Place Bound Top")
		(29 "B.CrtYd" user "Package Geometry/Place Bound Bottom")
		(35 "F.Fab" user "Ref Des/Assembly Top")
		(33 "B.Fab" user "Ref Des/Assembly Bottom")
	)
	(footprint ""
		(layer "F.Cu")
		(at 33.093152 -68.525644 90)
		(property "Reference" "C1D34"
			(at 0 0 90)
			(layer "F.SilkS")
			(hide yes)
			(effects
				(font
					(size 1.27 1.27)
				)
			)
		)
		(property "Value" ""
			(at 0 0 90)
			(layer "F.Fab")
			(effects
				(font
					(size 1.27 1.27)
				)
			)
		)
		(duplicate_pad_numbers_are_jumpers no)
		(fp_rect
			(start 0.3048 0.9906)
			(end -0.3048 -0.1016)
			(stroke
				(width 0)
				(type default)
			)
			(fill no)
			(layer "F.CrtYd")
		)
		(fp_line
			(start 0.3048 -0.1016)
			(end -0.3048 -0.1016)
			(stroke
				(width 0.1)
				(type default)
			)
			(layer "F.Fab")
		)
		(fp_line
			(start -0.3048 -0.1016)
			(end -0.3048 0.9906)
			(stroke
				(width 0.1)
				(type default)
			)
			(layer "F.Fab")
		)
		(fp_line
			(start 0.3048 0.9906)
			(end 0.3048 -0.1016)
			(stroke
				(width 0.1)
				(type default)
			)
			(layer "F.Fab")
		)
		(fp_line
			(start -0.3048 0.9906)
			(end 0.3048 0.9906)
			(stroke
				(width 0.1)
				(type default)
			)
			(layer "F.Fab")
		)
		(pad "1" smd rect
			(at 0 0 90)
			(size 0.508 0.508)
			(layers "F.Cu" "F.Mask" "F.Paste")
			(net "VR_FET_SW_P12V_STBY_PVCCIN_CPU1")
		)
		(pad "2" smd rect
			(at 0 0.889 90)
			(size 0.508 0.508)
			(layers "F.Cu" "F.Mask" "F.Paste")
			(net "GND")
		)
		(zone
			(layer "F.Cu")
			(hatch none 0.5)
			(connect_pads
				(clearance 0)
			)
			(min_thickness 0.25)
			(keepout
				(tracks allowed)
				(vias not_allowed)
				(pads allowed)
				(copperpour not_allowed)
				(footprints allowed)
			)
			(placement
				(enabled no)
				(sheetname "")
			)
			(fill
				(thermal_gap 0.5)
				(thermal_bridge_width 0.5)
				(island_removal_mode 0)
			)
			(polygon
				(pts
					(xy 33.728152 -68.779644) (xy 33.347152 -68.779644) (xy 33.347152 -68.271644) (xy 33.728152 -68.271644)
				)
			)
		)
		(zone
			(layer "F.Cu")
			(hatch none 0.5)
			(connect_pads
				(clearance 0)
			)
			(min_thickness 0.25)
			(keepout
				(tracks not_allowed)
				(vias allowed)
				(pads allowed)
				(copperpour not_allowed)
				(footprints allowed)
			)
			(placement
				(enabled no)
				(sheetname "")
			)
			(fill
				(thermal_gap 0.5)
				(thermal_bridge_width 0.5)
				(island_removal_mode 0)
			)
			(polygon
				(pts
					(xy 33.728152 -68.779644) (xy 33.347152 -68.779644) (xy 33.347152 -68.271644) (xy 33.728152 -68.271644)
				)
			)
		)
	)
	(footprint ""
		(layer "F.Cu")
		(at 477.8756 -45.1739 180)
		(property "Reference" "C9E7"
			(at 0 0 180)
			(layer "F.SilkS")
			(hide yes)
			(effects
				(font
					(size 1.27 1.27)
				)
			)
		)
		(property "Value" ""
			(at 0 0 180)
			(layer "F.Fab")
			(effects
				(font
					(size 1.27 1.27)
				)
			)
		)
		(duplicate_pad_numbers_are_jumpers no)
		(fp_poly
			(pts
				(xy 0.3048 -0.1016) (xy 0.3048 0.9906) (xy -0.3048 0.9906) (xy -0.3048 -0.1016)
			)
			(stroke
				(width 0)
				(type default)
			)
			(fill no)
			(layer "F.CrtYd")
		)
		(fp_line
			(start 0.3048 0.9906)
			(end 0.3048 -0.1016)
			(stroke
				(width 0.1)
				(type default)
			)
			(layer "F.Fab")
		)
		(fp_line
			(start 0.3048 -0.1016)
			(end -0.3048 -0.1016)
			(stroke
				(width 0.1)
				(type default)
			)
			(layer "F.Fab")
		)
		(fp_line
			(start -0.3048 0.9906)
			(end 0.3048 0.9906)
			(stroke
				(width 0.1)
				(type default)
			)
			(layer "F.Fab")
		)
		(fp_line
			(start -0.3048 -0.1016)
			(end -0.3048 0.9906)
			(stroke
				(width 0.1)
				(type default)
			)
			(layer "F.Fab")
		)
		(pad "1" smd rect
			(at 0 0 180)
			(size 0.508 0.508)
			(layers "F.Cu" "F.Mask" "F.Paste")
			(net "A_CTOP")
		)
		(pad "2" smd rect
			(at 0 0.889 180)
			(size 0.508 0.508)
			(layers "F.Cu" "F.Mask" "F.Paste")
			(net "A_CBOT")
		)
		(zone
			(layer "F.Cu")
			(hatch none 0.5)
			(connect_pads
				(clearance 0)
			)
			(min_thickness 0.25)
			(keepout
				(tracks not_allowed)
				(vias allowed)
				(pads allowed)
				(copperpour not_allowed)
				(footprints allowed)
			)
			(placement
				(enabled no)
				(sheetname "")
			)
			(fill
				(thermal_gap 0.5)
				(thermal_bridge_width 0.5)
				(island_removal_mode 0)
			)
			(polygon
				(pts
					(xy 478.1296 -45.8089) (xy 477.6216 -45.8089) (xy 477.6216 -45.4279) (xy 478.1296 -45.4279)
				)
			)
		)
		(zone
			(layer "F.Cu")
			(hatch none 0.5)
			(connect_pads
				(clearance 0)
			)
			(min_thickness 0.25)
			(keepout
				(tracks allowed)
				(vias not_allowed)
				(pads allowed)
				(copperpour not_allowed)
				(footprints allowed)
			)
			(placement
				(enabled no)
				(sheetname "")
			)
			(fill
				(thermal_gap 0.5)
				(thermal_bridge_width 0.5)
				(island_removal_mode 0)
			)
			(polygon
				(pts
					(xy 478.1296 -45.4279) (xy 477.6216 -45.4279) (xy 477.6216 -45.8089) (xy 478.1296 -45.8089)
				)
			)
		)
	)
	(footprint ""
		(layer "F.Cu")
		(at 404.9522 -128.3335)
		(property "Reference" "C8B4"
			(at 0 0 0)
			(layer "F.SilkS")
			(hide yes)
			(effects
				(font
					(size 1.27 1.27)
				)
			)
		)
		(property "Value" ""
			(at 0 0 0)
			(layer "F.Fab")
			(effects
				(font
					(size 1.27 1.27)
				)
			)
		)
		(duplicate_pad_numbers_are_jumpers no)
		(fp_poly
			(pts
				(xy -0.4953 -0.2032) (xy 0.4953 -0.2032) (xy 0.4953 1.6002) (xy -0.4953 1.6002)
			)
			(stroke
				(width 0)
				(type default)
			)
			(fill no)
			(layer "F.CrtYd")
		)
		(fp_line
			(start -0.4953 -0.2032)
			(end 0.4953 -0.2032)
			(stroke
				(width 0.1)
				(type default)
			)
			(layer "F.Fab")
		)
		(fp_line
			(start -0.4953 1.6002)
			(end -0.4953 -0.2032)
			(stroke
				(width 0.1)
				(type default)
			)
			(layer "F.Fab")
		)
		(fp_line
			(start 0.4953 -0.2032)
			(end 0.4953 1.6002)
			(stroke
				(width 0.1)
				(type default)
			)
			(layer "F.Fab")
		)
		(fp_line
			(start 0.4953 1.6002)
			(end -0.4953 1.6002)
			(stroke
				(width 0.1)
				(type default)
			)
			(layer "F.Fab")
		)
		(pad "1" smd rect
			(at 0 0)
			(size 0.762 0.889)
			(layers "F.Cu" "F.Mask" "F.Paste")
			(net "P1V8_PCH_STBY")
		)
		(pad "2" smd rect
			(at 0 1.397)
			(size 0.762 0.889)
			(layers "F.Cu" "F.Mask" "F.Paste")
			(net "GND")
		)
		(zone
			(layer "F.Cu")
			(hatch none 0.5)
			(connect_pads
				(clearance 0)
			)
			(min_thickness 0.25)
			(keepout
				(tracks not_allowed)
				(vias allowed)
				(pads allowed)
				(copperpour not_allowed)
				(footprints allowed)
			)
			(placement
				(enabled no)
				(sheetname "")
			)
			(fill
				(thermal_gap 0.5)
				(thermal_bridge_width 0.5)
				(island_removal_mode 0)
			)
			(polygon
				(pts
					(xy 404.5712 -127.889) (xy 405.3332 -127.889) (xy 405.3332 -127.381) (xy 404.5712 -127.381)
				)
			)
		)
	)
)
